(kicad_pcb
	(version 20260206)
	(generator "pcbnew")
	(generator_version "10.0")
	(general
		(thickness 1.6)
		(legacy_teardrops no)
	)
	(paper "A4")
	(title_block
		(title "04192023_DAF0TMB3IC0_F0TG_MB_C_brd_V02_OCP.brd")
		(comment 1 "Grand Teton / footprints 1272-1277 of 8354")
	)
	(layers
		(0 "F.Cu" signal "TOP")
		(4 "In1.Cu" signal "GND")
		(6 "In2.Cu" signal "IN1")
		(8 "In3.Cu" signal "GND1")
		(10 "In4.Cu" signal "IN2")
		(12 "In5.Cu" signal "GND2")
		(14 "In6.Cu" signal "IN3")
		(16 "In7.Cu" signal "GND3")
		(18 "In8.Cu" signal "VCC")
		(20 "In9.Cu" signal "VCC1")
		(22 "In10.Cu" signal "GND4")
		(24 "In11.Cu" signal "IN4")
		(26 "In12.Cu" signal "GND5")
		(28 "In13.Cu" signal "IN5")
		(30 "In14.Cu" signal "GND6")
		(32 "In15.Cu" signal "IN6")
		(34 "In16.Cu" signal "GND7")
		(2 "B.Cu" signal "BOTTOM")
		(9 "F.Adhes" user "F.Adhesive")
		(11 "B.Adhes" user "B.Adhesive")
		(13 "F.Paste" user "Package Geometry/Pastemask Top")
		(15 "B.Paste" user "Package Geometry/Pastemask Bottom")
		(5 "F.SilkS" user "Ref Des/Silkscreen Top")
		(7 "B.SilkS" user "Ref Des/Silkscreen Bottom")
		(1 "F.Mask" user "Board Geometry/Soldermask Top")
		(3 "B.Mask" user "Board Geometry/Soldermask Bottom")
		(17 "Dwgs.User" user "User.Drawings")
		(19 "Cmts.User" user "User.Comments")
		(21 "Eco1.User" user "User.Eco1")
		(23 "Eco2.User" user "User.Eco2")
		(25 "Edge.Cuts" user "Board Geometry/Outline")
		(27 "Margin" user)
		(31 "F.CrtYd" user "Package Geometry/Place Bound Top")
		(29 "B.CrtYd" user "Package Geometry/Place Bound Bottom")
		(35 "F.Fab" user "Ref Des/Assembly Top")
		(33 "B.Fab" user "Ref Des/Assembly Bottom")
	)
	(footprint ""
		(layer "F.Cu")
		(at 170.46956 -387.763004 180)
		(property "Reference" "R852"
			(at 0 0 180)
			(layer "F.SilkS")
			(hide yes)
			(effects
				(font
					(size 1.27 1.27)
				)
			)
		)
		(property "Value" ""
			(at 0 0 180)
			(layer "F.Fab")
			(effects
				(font
					(size 1.27 1.27)
				)
			)
		)
		(duplicate_pad_numbers_are_jumpers no)
		(fp_line
			(start 0.7874 0.4064)
			(end -0.7874 0.4064)
			(stroke
				(width 0.1524)
				(type default)
			)
			(layer "F.SilkS")
		)
		(fp_line
			(start 0.7874 -0.4064)
			(end 0.7874 0.4064)
			(stroke
				(width 0.1524)
				(type default)
			)
			(layer "F.SilkS")
		)
		(fp_line
			(start -0.7874 0.4064)
			(end -0.7874 -0.4064)
			(stroke
				(width 0.1524)
				(type default)
			)
			(layer "F.SilkS")
		)
		(fp_line
			(start -0.7874 -0.4064)
			(end 0.7874 -0.4064)
			(stroke
				(width 0.1524)
				(type default)
			)
			(layer "F.SilkS")
		)
		(fp_line
			(start 0.67945 0.3048)
			(end 0.120396 0.3048)
			(stroke
				(width 0.1)
				(type default)
			)
			(layer "F.Fab")
		)
		(fp_line
			(start 0.67945 -0.3048)
			(end 0.67945 0.3048)
			(stroke
				(width 0.1)
				(type default)
			)
			(layer "F.Fab")
		)
		(fp_line
			(start 0.12065 -0.2794)
			(end 0.12065 -0.3048)
			(stroke
				(width 0.1)
				(type default)
			)
			(layer "F.Fab")
		)
		(fp_line
			(start 0.12065 -0.3048)
			(end 0.67945 -0.3048)
			(stroke
				(width 0.1)
				(type default)
			)
			(layer "F.Fab")
		)
		(fp_line
			(start 0.120396 0.3048)
			(end 0.120396 0.2794)
			(stroke
				(width 0.1)
				(type default)
			)
			(layer "F.Fab")
		)
		(fp_line
			(start 0.120396 0.2794)
			(end -0.12065 0.2794)
			(stroke
				(width 0.1)
				(type default)
			)
			(layer "F.Fab")
		)
		(fp_line
			(start -0.12065 0.3048)
			(end -0.67945 0.3048)
			(stroke
				(width 0.1)
				(type default)
			)
			(layer "F.Fab")
		)
		(fp_line
			(start -0.12065 0.2794)
			(end -0.12065 0.3048)
			(stroke
				(width 0.1)
				(type default)
			)
			(layer "F.Fab")
		)
		(fp_line
			(start -0.12065 -0.2794)
			(end 0.12065 -0.2794)
			(stroke
				(width 0.1)
				(type default)
			)
			(layer "F.Fab")
		)
		(fp_line
			(start -0.12065 -0.305054)
			(end -0.12065 -0.2794)
			(stroke
				(width 0.1)
				(type default)
			)
			(layer "F.Fab")
		)
		(fp_line
			(start -0.67945 0.3048)
			(end -0.67945 -0.305054)
			(stroke
				(width 0.1)
				(type default)
			)
			(layer "F.Fab")
		)
		(fp_line
			(start -0.67945 -0.305054)
			(end -0.12065 -0.305054)
			(stroke
				(width 0.1)
				(type default)
			)
			(layer "F.Fab")
		)
		(pad "1" smd rect
			(at -0.40005 0)
			(size 0.4572 0.508)
			(layers "F.Cu" "F.Mask" "F.Paste")
			(net "P1V8_CPU1_RT2_1A_1D")
		)
		(pad "2" smd rect
			(at 0.40005 0)
			(size 0.4572 0.508)
			(layers "F.Cu" "F.Mask" "F.Paste")
			(net "P1V8_CPU1_RT2_1A")
		)
	)
	(footprint ""
		(layer "F.Cu")
		(at 137.955274 -31.70682 90)
		(property "Reference" "R6203"
			(at 0 0 90)
			(layer "F.SilkS")
			(hide yes)
			(effects
				(font
					(size 1.27 1.27)
				)
			)
		)
		(property "Value" ""
			(at 0 0 90)
			(layer "F.Fab")
			(effects
				(font
					(size 1.27 1.27)
				)
			)
		)
		(duplicate_pad_numbers_are_jumpers no)
		(fp_line
			(start 0.7874 -0.4064)
			(end 0.7874 0.4064)
			(stroke
				(width 0.1524)
				(type default)
			)
			(layer "F.SilkS")
		)
		(fp_line
			(start -0.7874 -0.4064)
			(end 0.7874 -0.4064)
			(stroke
				(width 0.1524)
				(type default)
			)
			(layer "F.SilkS")
		)
		(fp_line
			(start 0.7874 0.4064)
			(end -0.7874 0.4064)
			(stroke
				(width 0.1524)
				(type default)
			)
			(layer "F.SilkS")
		)
		(fp_line
			(start -0.7874 0.4064)
			(end -0.7874 -0.4064)
			(stroke
				(width 0.1524)
				(type default)
			)
			(layer "F.SilkS")
		)
		(fp_line
			(start -0.12065 -0.305054)
			(end -0.12065 -0.2794)
			(stroke
				(width 0.1)
				(type default)
			)
			(layer "F.Fab")
		)
		(fp_line
			(start -0.67945 -0.305054)
			(end -0.12065 -0.305054)
			(stroke
				(width 0.1)
				(type default)
			)
			(layer "F.Fab")
		)
		(fp_line
			(start 0.67945 -0.3048)
			(end 0.67945 0.3048)
			(stroke
				(width 0.1)
				(type default)
			)
			(layer "F.Fab")
		)
		(fp_line
			(start 0.12065 -0.3048)
			(end 0.67945 -0.3048)
			(stroke
				(width 0.1)
				(type default)
			)
			(layer "F.Fab")
		)
		(fp_line
			(start 0.12065 -0.2794)
			(end 0.12065 -0.3048)
			(stroke
				(width 0.1)
				(type default)
			)
			(layer "F.Fab")
		)
		(fp_line
			(start -0.12065 -0.2794)
			(end 0.12065 -0.2794)
			(stroke
				(width 0.1)
				(type default)
			)
			(layer "F.Fab")
		)
		(fp_line
			(start 0.120396 0.2794)
			(end -0.12065 0.2794)
			(stroke
				(width 0.1)
				(type default)
			)
			(layer "F.Fab")
		)
		(fp_line
			(start -0.12065 0.2794)
			(end -0.12065 0.3048)
			(stroke
				(width 0.1)
				(type default)
			)
			(layer "F.Fab")
		)
		(fp_line
			(start 0.67945 0.3048)
			(end 0.120396 0.3048)
			(stroke
				(width 0.1)
				(type default)
			)
			(layer "F.Fab")
		)
		(fp_line
			(start 0.120396 0.3048)
			(end 0.120396 0.2794)
			(stroke
				(width 0.1)
				(type default)
			)
			(layer "F.Fab")
		)
		(fp_line
			(start -0.12065 0.3048)
			(end -0.67945 0.3048)
			(stroke
				(width 0.1)
				(type default)
			)
			(layer "F.Fab")
		)
		(fp_line
			(start -0.67945 0.3048)
			(end -0.67945 -0.305054)
			(stroke
				(width 0.1)
				(type default)
			)
			(layer "F.Fab")
		)
		(pad "1" smd circle
			(at -0.40005 0 90)
			(size 0 0)
			(layers "F.Cu" "F.Mask" "F.Paste")
			(net "GND")
		)
		(pad "2" smd circle
			(at 0.40005 0 90)
			(size 0 0)
			(layers "F.Cu" "F.Mask" "F.Paste")
			(net "USB_CPU0_HUB1_RREF_USB2")
		)
	)
	(footprint ""
		(layer "F.Cu")
		(at 191.295782 -29.283152 180)
		(property "Reference" "PC2236"
			(at 0 0 180)
			(layer "F.SilkS")
			(hide yes)
			(effects
				(font
					(size 1.27 1.27)
				)
			)
		)
		(property "Value" ""
			(at 0 0 180)
			(layer "F.Fab")
			(effects
				(font
					(size 1.27 1.27)
				)
			)
		)
		(duplicate_pad_numbers_are_jumpers no)
		(fp_line
			(start 0.7874 0.4064)
			(end -0.7874 0.4064)
			(stroke
				(width 0.1524)
				(type default)
			)
			(layer "F.SilkS")
		)
		(fp_line
			(start 0.7874 -0.4064)
			(end 0.7874 0.4064)
			(stroke
				(width 0.1524)
				(type default)
			)
			(layer "F.SilkS")
		)
		(fp_line
			(start -0.7874 0.4064)
			(end -0.7874 -0.4064)
			(stroke
				(width 0.1524)
				(type default)
			)
			(layer "F.SilkS")
		)
		(fp_line
			(start -0.7874 -0.4064)
			(end 0.7874 -0.4064)
			(stroke
				(width 0.1524)
				(type default)
			)
			(layer "F.SilkS")
		)
		(fp_line
			(start 0.67945 0.3048)
			(end 0.120396 0.3048)
			(stroke
				(width 0.1)
				(type default)
			)
			(layer "F.Fab")
		)
		(fp_line
			(start 0.67945 -0.3048)
			(end 0.67945 0.3048)
			(stroke
				(width 0.1)
				(type default)
			)
			(layer "F.Fab")
		)
		(fp_line
			(start 0.12065 -0.2794)
			(end 0.12065 -0.3048)
			(stroke
				(width 0.1)
				(type default)
			)
			(layer "F.Fab")
		)
		(fp_line
			(start 0.12065 -0.3048)
			(end 0.67945 -0.3048)
			(stroke
				(width 0.1)
				(type default)
			)
			(layer "F.Fab")
		)
		(fp_line
			(start 0.120396 0.3048)
			(end 0.120396 0.2794)
			(stroke
				(width 0.1)
				(type default)
			)
			(layer "F.Fab")
		)
		(fp_line
			(start 0.120396 0.2794)
			(end -0.12065 0.2794)
			(stroke
				(width 0.1)
				(type default)
			)
			(layer "F.Fab")
		)
		(fp_line
			(start -0.12065 0.3048)
			(end -0.67945 0.3048)
			(stroke
				(width 0.1)
				(type default)
			)
			(layer "F.Fab")
		)
		(fp_line
			(start -0.12065 0.2794)
			(end -0.12065 0.3048)
			(stroke
				(width 0.1)
				(type default)
			)
			(layer "F.Fab")
		)
		(fp_line
			(start -0.12065 -0.2794)
			(end 0.12065 -0.2794)
			(stroke
				(width 0.1)
				(type default)
			)
			(layer "F.Fab")
		)
		(fp_line
			(start -0.12065 -0.305054)
			(end -0.12065 -0.2794)
			(stroke
				(width 0.1)
				(type default)
			)
			(layer "F.Fab")
		)
		(fp_line
			(start -0.67945 0.3048)
			(end -0.67945 -0.305054)
			(stroke
				(width 0.1)
				(type default)
			)
			(layer "F.Fab")
		)
		(fp_line
			(start -0.67945 -0.305054)
			(end -0.12065 -0.305054)
			(stroke
				(width 0.1)
				(type default)
			)
			(layer "F.Fab")
		)
		(pad "1" smd circle
			(at -0.40005 0 180)
			(size 0 0)
			(layers "F.Cu" "F.Mask" "F.Paste")
			(net "P12V_SCM_R")
		)
		(pad "2" smd circle
			(at 0.40005 0 180)
			(size 0 0)
			(layers "F.Cu" "F.Mask" "F.Paste")
			(net "P12V_SCM_GATE")
		)
	)
	(footprint ""
		(layer "F.Cu")
		(at 131.64058 -27.52598 90)
		(property "Reference" "R6191"
			(at 0 0 90)
			(layer "F.SilkS")
			(hide yes)
			(effects
				(font
					(size 1.27 1.27)
				)
			)
		)
		(property "Value" ""
			(at 0 0 90)
			(layer "F.Fab")
			(effects
				(font
					(size 1.27 1.27)
				)
			)
		)
		(duplicate_pad_numbers_are_jumpers no)
		(fp_line
			(start 0.32512 -0.175006)
			(end 0.32512 0.175006)
			(stroke
				(width 0.1)
				(type default)
			)
			(layer "F.Fab")
		)
		(fp_line
			(start -0.32512 -0.175006)
			(end 0.32512 -0.175006)
			(stroke
				(width 0.1)
				(type default)
			)
			(layer "F.Fab")
		)
		(fp_line
			(start 0.32512 0.175006)
			(end -0.32512 0.175006)
			(stroke
				(width 0.1)
				(type default)
			)
			(layer "F.Fab")
		)
		(fp_line
			(start -0.32512 0.175006)
			(end -0.32512 -0.175006)
			(stroke
				(width 0.1)
				(type default)
			)
			(layer "F.Fab")
		)
		(pad "1" smd rect
			(at -0.2667 0 90)
			(size 0.3048 0.381)
			(layers "F.Cu" "F.Mask" "F.Paste")
			(net "USB2_CPU0_P0_DN")
		)
		(pad "2" smd rect
			(at 0.2667 0 270)
			(size 0.3048 0.381)
			(layers "F.Cu" "F.Mask" "F.Paste")
			(net "USB2_CPU0_P0_R1_DN")
		)
	)
	(footprint ""
		(layer "F.Cu")
		(at 265.006074 -140.624814 180)
		(property "Reference" "R8006"
			(at 0 0 180)
			(layer "F.SilkS")
			(hide yes)
			(effects
				(font
					(size 1.27 1.27)
				)
			)
		)
		(property "Value" ""
			(at 0 0 180)
			(layer "F.Fab")
			(effects
				(font
					(size 1.27 1.27)
				)
			)
		)
		(duplicate_pad_numbers_are_jumpers no)
		(fp_line
			(start 0.7874 0.4064)
			(end -0.7874 0.4064)
			(stroke
				(width 0.1524)
				(type default)
			)
			(layer "F.SilkS")
		)
		(fp_line
			(start 0.7874 -0.4064)
			(end 0.7874 0.4064)
			(stroke
				(width 0.1524)
				(type default)
			)
			(layer "F.SilkS")
		)
		(fp_line
			(start -0.7874 0.4064)
			(end -0.7874 -0.4064)
			(stroke
				(width 0.1524)
				(type default)
			)
			(layer "F.SilkS")
		)
		(fp_line
			(start -0.7874 -0.4064)
			(end 0.7874 -0.4064)
			(stroke
				(width 0.1524)
				(type default)
			)
			(layer "F.SilkS")
		)
		(fp_line
			(start 0.67945 0.3048)
			(end 0.120396 0.3048)
			(stroke
				(width 0.1)
				(type default)
			)
			(layer "F.Fab")
		)
		(fp_line
			(start 0.67945 -0.3048)
			(end 0.67945 0.3048)
			(stroke
				(width 0.1)
				(type default)
			)
			(layer "F.Fab")
		)
		(fp_line
			(start 0.12065 -0.2794)
			(end 0.12065 -0.3048)
			(stroke
				(width 0.1)
				(type default)
			)
			(layer "F.Fab")
		)
		(fp_line
			(start 0.12065 -0.3048)
			(end 0.67945 -0.3048)
			(stroke
				(width 0.1)
				(type default)
			)
			(layer "F.Fab")
		)
		(fp_line
			(start 0.120396 0.3048)
			(end 0.120396 0.2794)
			(stroke
				(width 0.1)
				(type default)
			)
			(layer "F.Fab")
		)
		(fp_line
			(start 0.120396 0.2794)
			(end -0.12065 0.2794)
			(stroke
				(width 0.1)
				(type default)
			)
			(layer "F.Fab")
		)
		(fp_line
			(start -0.12065 0.3048)
			(end -0.67945 0.3048)
			(stroke
				(width 0.1)
				(type default)
			)
			(layer "F.Fab")
		)
		(fp_line
			(start -0.12065 0.2794)
			(end -0.12065 0.3048)
			(stroke
				(width 0.1)
				(type default)
			)
			(layer "F.Fab")
		)
		(fp_line
			(start -0.12065 -0.2794)
			(end 0.12065 -0.2794)
			(stroke
				(width 0.1)
				(type default)
			)
			(layer "F.Fab")
		)
		(fp_line
			(start -0.12065 -0.305054)
			(end -0.12065 -0.2794)
			(stroke
				(width 0.1)
				(type default)
			)
			(layer "F.Fab")
		)
		(fp_line
			(start -0.67945 0.3048)
			(end -0.67945 -0.305054)
			(stroke
				(width 0.1)
				(type default)
			)
			(layer "F.Fab")
		)
		(fp_line
			(start -0.67945 -0.305054)
			(end -0.12065 -0.305054)
			(stroke
				(width 0.1)
				(type default)
			)
			(layer "F.Fab")
		)
		(pad "1" smd circle
			(at -0.40005 0 180)
			(size 0 0)
			(layers "F.Cu" "F.Mask" "F.Paste")
			(net "SPI_CPU0_D2")
		)
		(pad "2" smd circle
			(at 0.40005 0 180)
			(size 0 0)
			(layers "F.Cu" "F.Mask" "F.Paste")
			(net "SPI_CPU0_R1_D2")
		)
	)
	(footprint ""
		(layer "F.Cu")
		(at 153.416508 -43.61053)
		(property "Reference" "U98"
			(at -1.397 -2.13233 0)
			(unlocked yes)
			(layer "F.SilkS")
			(effects
				(font
					(size 0.7874 0.5842)
					(thickness 0.1524)
				)
				(justify left)
			)
		)
		(property "Value" ""
			(at 0 0 0)
			(layer "F.Fab")
			(effects
				(font
					(size 1.27 1.27)
				)
			)
		)
		(duplicate_pad_numbers_are_jumpers no)
		(fp_line
			(start -1.3208 -1.525016)
			(end -0.508 -1.525016)
			(stroke
				(width 0.1524)
				(type default)
			)
			(layer "F.SilkS")
		)
		(fp_line
			(start -1.3208 1.525016)
			(end -1.3208 -1.525016)
			(stroke
				(width 0.1524)
				(type default)
			)
			(layer "F.SilkS")
		)
		(fp_line
			(start -0.508 -1.525016)
			(end 0 -0.999998)
			(stroke
				(width 0.1524)
				(type default)
			)
			(layer "F.SilkS")
		)
		(fp_line
			(start 0 -0.999998)
			(end 0.508 -1.525016)
			(stroke
				(width 0.1524)
				(type default)
			)
			(layer "F.SilkS")
		)
		(fp_line
			(start 0.508 -1.525016)
			(end 1.3208 -1.525016)
			(stroke
				(width 0.1524)
				(type default)
			)
			(layer "F.SilkS")
		)
		(fp_line
			(start 1.3208 -1.525016)
			(end 1.3208 1.525016)
			(stroke
				(width 0.1524)
				(type default)
			)
			(layer "F.SilkS")
		)
		(fp_line
			(start 1.3208 1.525016)
			(end -1.3208 1.525016)
			(stroke
				(width 0.1524)
				(type default)
			)
			(layer "F.SilkS")
		)
		(fp_poly
			(pts
				(xy -2.176018 -2.256282) (xy -2.557018 -1.494282) (xy -2.938018 -2.256282)
			)
			(stroke
				(width 0)
				(type default)
			)
			(fill yes)
			(layer "F.SilkS")
		)
		(fp_line
			(start -3.037078 -1.20777)
			(end -1.524 -1.20777)
			(stroke
				(width 0.1)
				(type default)
			)
			(layer "F.Fab")
		)
		(fp_line
			(start -3.037078 1.203706)
			(end -3.037078 -1.20777)
			(stroke
				(width 0.1)
				(type default)
			)
			(layer "F.Fab")
		)
		(fp_line
			(start -1.5494 1.203706)
			(end -3.037078 1.203706)
			(stroke
				(width 0.1)
				(type default)
			)
			(layer "F.Fab")
		)
		(fp_line
			(start -1.5494 1.5494)
			(end -1.5494 1.203706)
			(stroke
				(width 0.1)
				(type default)
			)
			(layer "F.Fab")
		)
		(fp_line
			(start -1.524 -1.524)
			(end 1.524 -1.524)
			(stroke
				(width 0.1)
				(type default)
			)
			(layer "F.Fab")
		)
		(fp_line
			(start -1.524 -1.20777)
			(end -1.524 -1.524)
			(stroke
				(width 0.1)
				(type default)
			)
			(layer "F.Fab")
		)
		(fp_line
			(start 1.524 -1.524)
			(end 1.524 -1.20777)
			(stroke
				(width 0.1)
				(type default)
			)
			(layer "F.Fab")
		)
		(fp_line
			(start 1.524 -1.20777)
			(end 3.0353 -1.20777)
			(stroke
				(width 0.1)
				(type default)
			)
			(layer "F.Fab")
		)
		(fp_line
			(start 1.524 1.208786)
			(end 1.524 1.5494)
			(stroke
				(width 0.1)
				(type default)
			)
			(layer "F.Fab")
		)
		(fp_line
			(start 1.524 1.5494)
			(end -1.5494 1.5494)
			(stroke
				(width 0.1)
				(type default)
			)
			(layer "F.Fab")
		)
		(fp_line
			(start 3.0353 -1.20777)
			(end 3.0353 1.208786)
			(stroke
				(width 0.1)
				(type default)
			)
			(layer "F.Fab")
		)
		(fp_line
			(start 3.0353 1.208786)
			(end 1.524 1.208786)
			(stroke
				(width 0.1)
				(type default)
			)
			(layer "F.Fab")
		)
		(fp_poly
			(pts
				(xy -3.175 -1.016) (xy -3.937 -0.635) (xy -3.937 -1.397)
			)
			(stroke
				(width 0)
				(type default)
			)
			(fill yes)
			(layer "F.Fab")
		)
		(pad "1" smd rect
			(at -2.234946 -0.975106 270)
			(size 0.3556 1.4986)
			(layers "F.Cu" "F.Mask" "F.Paste")
			(net "GND")
		)
		(pad "2" smd rect
			(at -2.234946 -0.32512 270)
			(size 0.3556 1.4986)
			(layers "F.Cu" "F.Mask" "F.Paste")
			(net "P1V8_AUX")
		)
		(pad "3" smd rect
			(at -2.234946 0.32512 270)
			(size 0.3556 1.4986)
			(layers "F.Cu" "F.Mask" "F.Paste")
			(net "SMB_M2_P1_1V8AUX_SCL_R")
		)
		(pad "4" smd rect
			(at -2.234946 0.975106 270)
			(size 0.3556 1.4986)
			(layers "F.Cu" "F.Mask" "F.Paste")
			(net "SMB_M2_P1_1V8AUX_SDA_R")
		)
		(pad "5" smd rect
			(at 2.234946 0.975106 270)
			(size 0.3556 1.4986)
			(layers "F.Cu" "F.Mask" "F.Paste")
			(net "SMB_SENSOR_M2_P1_3V3AUX_SDA")
		)
		(pad "6" smd rect
			(at 2.234946 0.32512 270)
			(size 0.3556 1.4986)
			(layers "F.Cu" "F.Mask" "F.Paste")
			(net "SMB_SENSOR_M2_P1_3V3AUX_SCL")
		)
		(pad "7" smd rect
			(at 2.234946 -0.32512 270)
			(size 0.3556 1.4986)
			(layers "F.Cu" "F.Mask" "F.Paste")
			(net "SMB_PCIE_M2_0_EN")
		)
		(pad "8" smd rect
			(at 2.234946 -0.975106 270)
			(size 0.3556 1.4986)
			(layers "F.Cu" "F.Mask" "F.Paste")
			(net "SMB_PCIE_M2_0_EN")
		)
	)
)
